(kicad_pcb
	(version 20260206)
	(generator "pcbnew")
	(generator_version "10.0")
	(general
		(thickness 1.6)
		(legacy_teardrops no)
	)
	(paper "A4")
	(title_block
		(title "Bryce Canyon_R.DPB_16317-1_OCP.brd")
		(comment 1 "Bryce Canyon / footprints 1113-1120 of 2099")
	)
	(layers
		(0 "F.Cu" signal "TOP")
		(4 "In1.Cu" signal "L2GND")
		(6 "In2.Cu" signal "L3")
		(8 "In3.Cu" signal "L4VCC")
		(10 "In4.Cu" signal "L5VCC")
		(12 "In5.Cu" signal "L6")
		(14 "In6.Cu" signal "L7GND")
		(2 "B.Cu" signal "BOTTOM")
		(9 "F.Adhes" user "F.Adhesive")
		(11 "B.Adhes" user "B.Adhesive")
		(13 "F.Paste" user "Package Geometry/Pastemask Top")
		(15 "B.Paste" user "Package Geometry/Pastemask Bottom")
		(5 "F.SilkS" user "Ref Des/Silkscreen Top")
		(7 "B.SilkS" user "Ref Des/Silkscreen Bottom")
		(1 "F.Mask" user "Board Geometry/Soldermask Top")
		(3 "B.Mask" user "Board Geometry/Soldermask Bottom")
		(17 "Dwgs.User" user "User.Drawings")
		(19 "Cmts.User" user "User.Comments")
		(21 "Eco1.User" user "User.Eco1")
		(23 "Eco2.User" user "User.Eco2")
		(25 "Edge.Cuts" user "Board Geometry/Outline")
		(27 "Margin" user)
		(31 "F.CrtYd" user "Package Geometry/Place Bound Top")
		(29 "B.CrtYd" user "Package Geometry/Place Bound Bottom")
		(35 "F.Fab" user "Ref Des/Assembly Top")
		(33 "B.Fab" user "Ref Des/Assembly Bottom")
	)
	(footprint ""
		(layer "F.Cu")
		(at 426.2882 -135.6614 -90)
		(property "Reference" "C311"
			(at 0 0 270)
			(layer "F.SilkS")
			(hide yes)
			(effects
				(font
					(size 1.27 1.27)
				)
			)
		)
		(property "Value" "SCD033U25V2KX-GP"
			(at 1.1811 -2.7051 270)
			(unlocked yes)
			(layer "F.Fab")
			(hide yes)
			(effects
				(font
					(size 1.016 1.016)
					(thickness 0.1524)
				)
			)
		)
		(property "Device Type" "C402H22"
			(at 1.1811 -4.2291 270)
			(unlocked yes)
			(layer "F.Fab")
			(hide yes)
			(effects
				(font
					(size 1.016 1.016)
					(thickness 0.1524)
				)
			)
		)
		(duplicate_pad_numbers_are_jumpers no)
		(fp_rect
			(start -0.4318 0.9525)
			(end 0.4318 -0.9525)
			(stroke
				(width 0)
				(type default)
			)
			(fill no)
			(layer "F.CrtYd")
		)
		(fp_rect
			(start -0.4318 0.9525)
			(end 0.4318 -0.9525)
			(stroke
				(width 0)
				(type default)
			)
			(fill no)
			(layer "F.Fab")
		)
		(pad "1" smd custom
			(at 0 -0.4445 270)
			(size 0.1524 0.1524)
			(layers "F.Cu" "F.Mask" "F.Paste")
			(net "SW_HDD_P21")
			(options
				(clearance outline)
				(anchor circle)
			)
			(primitives
				(gr_poly
					(pts
						(arc
							(start 0.3048 -0.2032)
							(mid 0.275042 -0.275042)
							(end 0.2032 -0.3048)
						)
						(arc
							(start -0.2032 -0.3048)
							(mid -0.275042 -0.275042)
							(end -0.3048 -0.2032)
						)
						(arc
							(start -0.3048 0.2032)
							(mid -0.275042 0.275042)
							(end -0.2032 0.3048)
						)
						(arc
							(start 0.2032 0.3048)
							(mid 0.275042 0.275042)
							(end 0.3048 0.2032)
						)
					)
					(width 0)
					(fill yes)
				)
			)
		)
		(pad "2" smd custom
			(at 0 0.4445 270)
			(size 0.1524 0.1524)
			(layers "F.Cu" "F.Mask" "F.Paste")
			(net "GND")
			(options
				(clearance outline)
				(anchor circle)
			)
			(primitives
				(gr_poly
					(pts
						(arc
							(start 0.3048 -0.2032)
							(mid 0.275042 -0.275042)
							(end 0.2032 -0.3048)
						)
						(arc
							(start -0.2032 -0.3048)
							(mid -0.275042 -0.275042)
							(end -0.3048 -0.2032)
						)
						(arc
							(start -0.3048 0.2032)
							(mid -0.275042 0.275042)
							(end -0.2032 0.3048)
						)
						(arc
							(start 0.2032 0.3048)
							(mid 0.275042 0.275042)
							(end 0.3048 0.2032)
						)
					)
					(width 0)
					(fill yes)
				)
			)
		)
	)
	(footprint ""
		(layer "F.Cu")
		(at 308.701694 -212.390228 -90)
		(property "Reference" "R245"
			(at 0 0 270)
			(layer "F.SilkS")
			(hide yes)
			(effects
				(font
					(size 1.27 1.27)
				)
			)
		)
		(property "Value" "4K7R2F-GP"
			(at 0.064008 -3.993896 270)
			(unlocked yes)
			(layer "F.Fab")
			(hide yes)
			(effects
				(font
					(size 1.016 1.016)
					(thickness 0.1524)
				)
			)
		)
		(property "Device Type" "R402H16"
			(at 0.064008 -5.517896 270)
			(unlocked yes)
			(layer "F.Fab")
			(hide yes)
			(effects
				(font
					(size 1.016 1.016)
					(thickness 0.1524)
				)
			)
		)
		(duplicate_pad_numbers_are_jumpers no)
		(fp_line
			(start -0.508 -0.9398)
			(end -0.508 0.9398)
			(stroke
				(width 0.1524)
				(type default)
			)
			(layer "F.SilkS")
		)
		(fp_line
			(start 0.508 -0.9398)
			(end -0.508 -0.9398)
			(stroke
				(width 0.1524)
				(type default)
			)
			(layer "F.SilkS")
		)
		(fp_rect
			(start -0.508 0.9398)
			(end 0.508 -0.9398)
			(stroke
				(width 0)
				(type default)
			)
			(fill no)
			(layer "F.CrtYd")
		)
		(fp_rect
			(start -0.508 0.9398)
			(end 0.508 -0.9398)
			(stroke
				(width 0)
				(type default)
			)
			(fill no)
			(layer "F.Fab")
		)
		(pad "1" smd custom
			(at 0 -0.4445 270)
			(size 0.1397 0.1397)
			(layers "F.Cu" "F.Mask" "F.Paste")
			(net "DRIVE_B_6_ACT")
			(options
				(clearance outline)
				(anchor circle)
			)
			(primitives
				(gr_poly
					(pts
						(arc
							(start -0.1778 -0.2794)
							(mid -0.249642 -0.249642)
							(end -0.2794 -0.1778)
						)
						(arc
							(start -0.2794 0.1778)
							(mid -0.249642 0.249642)
							(end -0.1778 0.2794)
						)
						(arc
							(start 0.1778 0.2794)
							(mid 0.249642 0.249642)
							(end 0.2794 0.1778)
						)
						(arc
							(start 0.2794 -0.1778)
							(mid 0.249642 -0.249642)
							(end 0.1778 -0.2794)
						)
					)
					(width 0)
					(fill yes)
				)
			)
		)
		(pad "2" smd custom
			(at 0 0.4445 270)
			(size 0.1397 0.1397)
			(layers "F.Cu" "F.Mask" "F.Paste")
			(net "GND")
			(options
				(clearance outline)
				(anchor circle)
			)
			(primitives
				(gr_poly
					(pts
						(arc
							(start -0.1778 -0.2794)
							(mid -0.249642 -0.249642)
							(end -0.2794 -0.1778)
						)
						(arc
							(start -0.2794 0.1778)
							(mid -0.249642 0.249642)
							(end -0.1778 0.2794)
						)
						(arc
							(start 0.1778 0.2794)
							(mid 0.249642 0.249642)
							(end 0.2794 0.1778)
						)
						(arc
							(start 0.2794 -0.1778)
							(mid 0.249642 -0.249642)
							(end 0.1778 -0.2794)
						)
					)
					(width 0)
					(fill yes)
				)
			)
		)
	)
	(footprint ""
		(layer "F.Cu")
		(at 430.403 -13.589 180)
		(property "Reference" "R839"
			(at 0 0 180)
			(layer "F.SilkS")
			(hide yes)
			(effects
				(font
					(size 1.27 1.27)
				)
			)
		)
		(property "Value" "0R2J-2-GP"
			(at 0.064008 -3.993896 180)
			(unlocked yes)
			(layer "F.Fab")
			(hide yes)
			(effects
				(font
					(size 1.016 1.016)
					(thickness 0.1524)
				)
			)
		)
		(property "Device Type" "R402H16"
			(at 0.064008 -5.517896 180)
			(unlocked yes)
			(layer "F.Fab")
			(hide yes)
			(effects
				(font
					(size 1.016 1.016)
					(thickness 0.1524)
				)
			)
		)
		(duplicate_pad_numbers_are_jumpers no)
		(fp_line
			(start 0.508 -0.9398)
			(end -0.508 -0.9398)
			(stroke
				(width 0.1524)
				(type default)
			)
			(layer "F.SilkS")
		)
		(fp_line
			(start -0.508 -0.9398)
			(end -0.508 0.9398)
			(stroke
				(width 0.1524)
				(type default)
			)
			(layer "F.SilkS")
		)
		(fp_rect
			(start -0.508 0.9398)
			(end 0.508 -0.9398)
			(stroke
				(width 0)
				(type default)
			)
			(fill no)
			(layer "F.CrtYd")
		)
		(fp_rect
			(start -0.508 0.9398)
			(end 0.508 -0.9398)
			(stroke
				(width 0)
				(type default)
			)
			(fill no)
			(layer "F.Fab")
		)
		(pad "1" smd custom
			(at 0 -0.4445 180)
			(size 0.1397 0.1397)
			(layers "F.Cu" "F.Mask" "F.Paste")
			(net "DRIVE_B_33_PWR")
			(options
				(clearance outline)
				(anchor circle)
			)
			(primitives
				(gr_poly
					(pts
						(arc
							(start -0.1778 -0.2794)
							(mid -0.249642 -0.249642)
							(end -0.2794 -0.1778)
						)
						(arc
							(start -0.2794 0.1778)
							(mid -0.249642 0.249642)
							(end -0.1778 0.2794)
						)
						(arc
							(start 0.1778 0.2794)
							(mid 0.249642 0.249642)
							(end 0.2794 0.1778)
						)
						(arc
							(start 0.2794 -0.1778)
							(mid 0.249642 -0.249642)
							(end 0.1778 -0.2794)
						)
					)
					(width 0)
					(fill yes)
				)
			)
		)
		(pad "2" smd custom
			(at 0 0.4445 180)
			(size 0.1397 0.1397)
			(layers "F.Cu" "F.Mask" "F.Paste")
			(net "SW_PWR_R_HDD33")
			(options
				(clearance outline)
				(anchor circle)
			)
			(primitives
				(gr_poly
					(pts
						(arc
							(start -0.1778 -0.2794)
							(mid -0.249642 -0.249642)
							(end -0.2794 -0.1778)
						)
						(arc
							(start -0.2794 0.1778)
							(mid -0.249642 0.249642)
							(end -0.1778 0.2794)
						)
						(arc
							(start 0.1778 0.2794)
							(mid 0.249642 0.249642)
							(end 0.2794 0.1778)
						)
						(arc
							(start 0.2794 -0.1778)
							(mid 0.249642 -0.249642)
							(end 0.1778 -0.2794)
						)
					)
					(width 0)
					(fill yes)
				)
			)
		)
	)
	(footprint ""
		(layer "F.Cu")
		(at 190.812928 -372.347236 90)
		(property "Reference" "R1298"
			(at 0 0 90)
			(layer "F.SilkS")
			(hide yes)
			(effects
				(font
					(size 1.27 1.27)
				)
			)
		)
		(property "Value" "4K7R2F-GP"
			(at 0.064008 -3.993896 90)
			(unlocked yes)
			(layer "F.Fab")
			(hide yes)
			(effects
				(font
					(size 1.016 1.016)
					(thickness 0.1524)
				)
			)
		)
		(property "Device Type" "R402H16"
			(at 0.064008 -5.517896 90)
			(unlocked yes)
			(layer "F.Fab")
			(hide yes)
			(effects
				(font
					(size 1.016 1.016)
					(thickness 0.1524)
				)
			)
		)
		(duplicate_pad_numbers_are_jumpers no)
		(fp_line
			(start 0.508 -0.9398)
			(end -0.508 -0.9398)
			(stroke
				(width 0.1524)
				(type default)
			)
			(layer "F.SilkS")
		)
		(fp_line
			(start -0.508 -0.9398)
			(end -0.508 0.9398)
			(stroke
				(width 0.1524)
				(type default)
			)
			(layer "F.SilkS")
		)
		(fp_rect
			(start -0.508 0.9398)
			(end 0.508 -0.9398)
			(stroke
				(width 0)
				(type default)
			)
			(fill no)
			(layer "F.CrtYd")
		)
		(fp_rect
			(start -0.508 0.9398)
			(end 0.508 -0.9398)
			(stroke
				(width 0)
				(type default)
			)
			(fill no)
			(layer "F.Fab")
		)
		(pad "1" smd custom
			(at 0 -0.4445 90)
			(size 0.1397 0.1397)
			(layers "F.Cu" "F.Mask" "F.Paste")
			(net "FAN_YELLOW_LED1")
			(options
				(clearance outline)
				(anchor circle)
			)
			(primitives
				(gr_poly
					(pts
						(arc
							(start -0.1778 -0.2794)
							(mid -0.249642 -0.249642)
							(end -0.2794 -0.1778)
						)
						(arc
							(start -0.2794 0.1778)
							(mid -0.249642 0.249642)
							(end -0.1778 0.2794)
						)
						(arc
							(start 0.1778 0.2794)
							(mid 0.249642 0.249642)
							(end 0.2794 0.1778)
						)
						(arc
							(start 0.2794 -0.1778)
							(mid 0.249642 -0.249642)
							(end 0.1778 -0.2794)
						)
					)
					(width 0)
					(fill yes)
				)
			)
		)
		(pad "2" smd custom
			(at 0 0.4445 90)
			(size 0.1397 0.1397)
			(layers "F.Cu" "F.Mask" "F.Paste")
			(net "P12V_IN")
			(options
				(clearance outline)
				(anchor circle)
			)
			(primitives
				(gr_poly
					(pts
						(arc
							(start -0.1778 -0.2794)
							(mid -0.249642 -0.249642)
							(end -0.2794 -0.1778)
						)
						(arc
							(start -0.2794 0.1778)
							(mid -0.249642 0.249642)
							(end -0.1778 0.2794)
						)
						(arc
							(start 0.1778 0.2794)
							(mid 0.249642 0.249642)
							(end 0.2794 0.1778)
						)
						(arc
							(start 0.2794 -0.1778)
							(mid 0.249642 -0.249642)
							(end 0.1778 -0.2794)
						)
					)
					(width 0)
					(fill yes)
				)
			)
		)
	)
	(footprint ""
		(layer "F.Cu")
		(at 80.01 -17.653 180)
		(property "Reference" "D26"
			(at 0 0 180)
			(layer "F.SilkS")
			(hide yes)
			(effects
				(font
					(size 1.27 1.27)
				)
			)
		)
		(property "Value" "RB551V30-GP"
			(at 0 -6.7818 180)
			(unlocked yes)
			(layer "F.Fab")
			(hide yes)
			(effects
				(font
					(size 1.016 1.016)
					(thickness 0.1524)
				)
			)
		)
		(property "Device Type" "SOD323AKH38"
			(at 0 -8.6868 180)
			(unlocked yes)
			(layer "F.Fab")
			(hide yes)
			(effects
				(font
					(size 1.016 1.016)
					(thickness 0.1524)
				)
			)
		)
		(duplicate_pad_numbers_are_jumpers no)
		(fp_line
			(start 0.889 2.159)
			(end -0.889 2.159)
			(stroke
				(width 0.1524)
				(type default)
			)
			(layer "F.SilkS")
		)
		(fp_line
			(start 0.889 -1.9304)
			(end 0.889 2.159)
			(stroke
				(width 0.1524)
				(type default)
			)
			(layer "F.SilkS")
		)
		(fp_line
			(start 0.762 2.0574)
			(end -0.762 2.0574)
			(stroke
				(width 0.508)
				(type default)
			)
			(layer "F.SilkS")
		)
		(fp_line
			(start -0.889 2.159)
			(end -0.889 -1.9304)
			(stroke
				(width 0.1524)
				(type default)
			)
			(layer "F.SilkS")
		)
		(fp_line
			(start -0.889 -1.9304)
			(end 0.889 -1.9304)
			(stroke
				(width 0.1524)
				(type default)
			)
			(layer "F.SilkS")
		)
		(fp_rect
			(start -1.016 2.3114)
			(end 1.016 -2.0066)
			(stroke
				(width 0)
				(type default)
			)
			(fill no)
			(layer "F.CrtYd")
		)
		(fp_poly
			(pts
				(xy -1.016 -2.0066) (xy 1.016 -2.0066) (xy 1.016 2.3114) (xy -1.016 2.3114)
			)
			(stroke
				(width 0)
				(type default)
			)
			(fill no)
			(layer "F.Fab")
		)
		(pad "A" smd rect
			(at 0 -1.143 180)
			(size 0.5588 1.016)
			(layers "F.Cu" "F.Mask" "F.Paste")
			(net "SW_HDD_R26")
		)
		(pad "K" smd rect
			(at 0 1.143 180)
			(size 0.5588 1.016)
			(layers "F.Cu" "F.Mask" "F.Paste")
			(net "SW_HDD_N26")
		)
	)
	(footprint ""
		(layer "F.Cu")
		(at 318.356996 -372.0846)
		(property "Reference" "C712"
			(at 0 0 0)
			(layer "F.SilkS")
			(hide yes)
			(effects
				(font
					(size 1.27 1.27)
				)
			)
		)
		(property "Value" "SCD1U16V2KX-3GP"
			(at 1.1811 -2.7051 0)
			(unlocked yes)
			(layer "F.Fab")
			(hide yes)
			(effects
				(font
					(size 1.016 1.016)
					(thickness 0.1524)
				)
			)
		)
		(property "Device Type" "C402H22"
			(at 1.1811 -4.2291 0)
			(unlocked yes)
			(layer "F.Fab")
			(hide yes)
			(effects
				(font
					(size 1.016 1.016)
					(thickness 0.1524)
				)
			)
		)
		(duplicate_pad_numbers_are_jumpers no)
		(fp_rect
			(start -0.4318 0.9525)
			(end 0.4318 -0.9525)
			(stroke
				(width 0)
				(type default)
			)
			(fill no)
			(layer "F.CrtYd")
		)
		(fp_rect
			(start -0.4318 0.9525)
			(end 0.4318 -0.9525)
			(stroke
				(width 0)
				(type default)
			)
			(fill no)
			(layer "F.Fab")
		)
		(pad "1" smd custom
			(at 0 -0.4445)
			(size 0.1524 0.1524)
			(layers "F.Cu" "F.Mask" "F.Paste")
			(net "P3V3_IN")
			(options
				(clearance outline)
				(anchor circle)
			)
			(primitives
				(gr_poly
					(pts
						(arc
							(start 0.3048 -0.2032)
							(mid 0.275042 -0.275042)
							(end 0.2032 -0.3048)
						)
						(arc
							(start -0.2032 -0.3048)
							(mid -0.275042 -0.275042)
							(end -0.3048 -0.2032)
						)
						(arc
							(start -0.3048 0.2032)
							(mid -0.275042 0.275042)
							(end -0.2032 0.3048)
						)
						(arc
							(start 0.2032 0.3048)
							(mid 0.275042 0.275042)
							(end 0.3048 0.2032)
						)
					)
					(width 0)
					(fill yes)
				)
			)
		)
		(pad "2" smd custom
			(at 0 0.4445)
			(size 0.1524 0.1524)
			(layers "F.Cu" "F.Mask" "F.Paste")
			(net "GND")
			(options
				(clearance outline)
				(anchor circle)
			)
			(primitives
				(gr_poly
					(pts
						(arc
							(start 0.3048 -0.2032)
							(mid 0.275042 -0.275042)
							(end 0.2032 -0.3048)
						)
						(arc
							(start -0.2032 -0.3048)
							(mid -0.275042 -0.275042)
							(end -0.3048 -0.2032)
						)
						(arc
							(start -0.3048 0.2032)
							(mid -0.275042 0.275042)
							(end -0.2032 0.3048)
						)
						(arc
							(start 0.2032 0.3048)
							(mid 0.275042 0.275042)
							(end 0.3048 0.2032)
						)
					)
					(width 0)
					(fill yes)
				)
			)
		)
	)
	(footprint ""
		(layer "F.Cu")
		(at 474.345 -250.2408)
		(property "Reference" "R337"
			(at 0 0 0)
			(layer "F.SilkS")
			(hide yes)
			(effects
				(font
					(size 1.27 1.27)
				)
			)
		)
		(property "Value" "220R3F-1-GP"
			(at -0.0254 -2.5146 0)
			(unlocked yes)
			(layer "F.Fab")
			(hide yes)
			(effects
				(font
					(size 1.016 1.016)
					(thickness 0.1524)
				)
			)
		)
		(property "Device Type" "R603H22"
			(at -0.0254 -4.0386 0)
			(unlocked yes)
			(layer "F.Fab")
			(hide yes)
			(effects
				(font
					(size 1.016 1.016)
					(thickness 0.1524)
				)
			)
		)
		(duplicate_pad_numbers_are_jumpers no)
		(fp_line
			(start -0.4826 0)
			(end -0.2032 0)
			(stroke
				(width 0.2032)
				(type default)
			)
			(layer "F.SilkS")
		)
		(fp_line
			(start 0.2032 0)
			(end 0.4826 0)
			(stroke
				(width 0.2032)
				(type default)
			)
			(layer "F.SilkS")
		)
		(fp_rect
			(start -0.5842 1.3335)
			(end 0.5842 -1.3335)
			(stroke
				(width 0)
				(type default)
			)
			(fill no)
			(layer "F.CrtYd")
		)
		(fp_rect
			(start -0.5842 1.3335)
			(end 0.5842 -1.3335)
			(stroke
				(width 0)
				(type default)
			)
			(fill no)
			(layer "F.Fab")
		)
		(pad "1" smd custom
			(at 0 -0.762)
			(size 0.2159 0.2159)
			(layers "F.Cu" "F.Mask" "F.Paste")
			(net "HDD_PRSNT_11")
			(options
				(clearance outline)
				(anchor circle)
			)
			(primitives
				(gr_poly
					(pts
						(arc
							(start -0.3302 -0.4318)
							(mid -0.402042 -0.402042)
							(end -0.4318 -0.3302)
						)
						(arc
							(start -0.4318 0.3302)
							(mid -0.402042 0.402042)
							(end -0.3302 0.4318)
						)
						(arc
							(start 0.3302 0.4318)
							(mid 0.402042 0.402042)
							(end 0.4318 0.3302)
						)
						(arc
							(start 0.4318 -0.3302)
							(mid 0.402042 -0.402042)
							(end 0.3302 -0.4318)
						)
					)
					(width 0)
					(fill yes)
				)
			)
		)
		(pad "2" smd custom
			(at 0 0.762)
			(size 0.2159 0.2159)
			(layers "F.Cu" "F.Mask" "F.Paste")
			(net "DRIVE_B_11_INS")
			(options
				(clearance outline)
				(anchor circle)
			)
			(primitives
				(gr_poly
					(pts
						(arc
							(start -0.3302 -0.4318)
							(mid -0.402042 -0.402042)
							(end -0.4318 -0.3302)
						)
						(arc
							(start -0.4318 0.3302)
							(mid -0.402042 0.402042)
							(end -0.3302 0.4318)
						)
						(arc
							(start 0.3302 0.4318)
							(mid 0.402042 0.402042)
							(end 0.4318 0.3302)
						)
						(arc
							(start 0.4318 -0.3302)
							(mid 0.402042 -0.402042)
							(end 0.3302 -0.4318)
						)
					)
					(width 0)
					(fill yes)
				)
			)
		)
	)
	(footprint ""
		(layer "F.Cu")
		(at 255.509522 -358.622346)
		(property "Reference" "C554"
			(at 0 0 0)
			(layer "F.SilkS")
			(hide yes)
			(effects
				(font
					(size 1.27 1.27)
				)
			)
		)
		(property "Value" "SCD22U16V2KX-GP"
			(at 1.1811 -2.7051 0)
			(unlocked yes)
			(layer "F.Fab")
			(hide yes)
			(effects
				(font
					(size 1.016 1.016)
					(thickness 0.1524)
				)
			)
		)
		(property "Device Type" "C402H22"
			(at 1.1811 -4.2291 0)
			(unlocked yes)
			(layer "F.Fab")
			(hide yes)
			(effects
				(font
					(size 1.016 1.016)
					(thickness 0.1524)
				)
			)
		)
		(duplicate_pad_numbers_are_jumpers no)
		(fp_rect
			(start -0.4318 0.9525)
			(end 0.4318 -0.9525)
			(stroke
				(width 0)
				(type default)
			)
			(fill no)
			(layer "F.CrtYd")
		)
		(fp_rect
			(start -0.4318 0.9525)
			(end 0.4318 -0.9525)
			(stroke
				(width 0)
				(type default)
			)
			(fill no)
			(layer "F.Fab")
		)
		(pad "1" smd custom
			(at 0 -0.4445)
			(size 0.1524 0.1524)
			(layers "F.Cu" "F.Mask" "F.Paste")
			(net "MB3_TIME_R")
			(options
				(clearance outline)
				(anchor circle)
			)
			(primitives
				(gr_poly
					(pts
						(arc
							(start 0.3048 -0.2032)
							(mid 0.275042 -0.275042)
							(end 0.2032 -0.3048)
						)
						(arc
							(start -0.2032 -0.3048)
							(mid -0.275042 -0.275042)
							(end -0.3048 -0.2032)
						)
						(arc
							(start -0.3048 0.2032)
							(mid -0.275042 0.275042)
							(end -0.2032 0.3048)
						)
						(arc
							(start 0.2032 0.3048)
							(mid 0.275042 0.275042)
							(end 0.3048 0.2032)
						)
					)
					(width 0)
					(fill yes)
				)
			)
		)
		(pad "2" smd custom
			(at 0 0.4445)
			(size 0.1524 0.1524)
			(layers "F.Cu" "F.Mask" "F.Paste")
			(net "AGND_CURRENT_DPB")
			(options
				(clearance outline)
				(anchor circle)
			)
			(primitives
				(gr_poly
					(pts
						(arc
							(start 0.3048 -0.2032)
							(mid 0.275042 -0.275042)
							(end 0.2032 -0.3048)
						)
						(arc
							(start -0.2032 -0.3048)
							(mid -0.275042 -0.275042)
							(end -0.3048 -0.2032)
						)
						(arc
							(start -0.3048 0.2032)
							(mid -0.275042 0.275042)
							(end -0.2032 0.3048)
						)
						(arc
							(start 0.2032 0.3048)
							(mid 0.275042 0.275042)
							(end 0.3048 0.2032)
						)
					)
					(width 0)
					(fill yes)
				)
			)
		)
	)
)
